# BASEBOARD_FAB2 (Tioga Pass) — schematic netlist excerpt (pin names and nets, part order shuffled) for the footprints in the layout excerpt that follows; sources: Cadence DE-HDL packaged netlist, KiCad conversion of Wiwynn_Tioga_Pass_MB.brd

R1D18  RES  100.0K 1% CHIP  pkg 0402  page 199 : A = A_HSC_HIGH_EN ; B = AGND_HSC
C7A28  CAP  220PF 50V 10% X7R  pkg 0402LF  page 218 : A = VR_PVDDQ_DEF_AVSP ; B = VSENSE_PVDDQ_DEF_N
R1W19  RES  0.0 5% CHIP  pkg 0402  page 115 : A = USB2_P02_DN_R ; B = USB2_P02_DN

(kicad_pcb
	(version 20260206)
	(generator "pcbnew")
	(generator_version "10.0")
	(general
		(thickness 1.6)
		(legacy_teardrops no)
	)
	(paper "A4")
	(title_block
		(title "Wiwynn_Tioga_Pass_MB.brd")
		(comment 1 "Tioga Pass / footprints 2234-2236 of 4770")
	)
	(layers
		(0 "F.Cu" signal "TOP")
		(4 "In1.Cu" signal "L2GND")
		(6 "In2.Cu" signal "L3")
		(8 "In3.Cu" signal "L4GND")
		(10 "In4.Cu" signal "L5")
		(12 "In5.Cu" signal "L6GND")
		(14 "In6.Cu" signal "L7VCC")
		(16 "In7.Cu" signal "L8VCC")
		(18 "In8.Cu" signal "L9GND")
		(20 "In9.Cu" signal "L10")
		(22 "In10.Cu" signal "L11GND")
		(24 "In11.Cu" signal "L12")
		(26 "In12.Cu" signal "L13GND")
		(2 "B.Cu" signal "BOTTOM")
		(9 "F.Adhes" user "F.Adhesive")
		(11 "B.Adhes" user "B.Adhesive")
		(13 "F.Paste" user "Package Geometry/Pastemask Top")
		(15 "B.Paste" user "Package Geometry/Pastemask Bottom")
		(5 "F.SilkS" user "Ref Des/Silkscreen Top")
		(7 "B.SilkS" user "Ref Des/Silkscreen Bottom")
		(1 "F.Mask" user "Board Geometry/Soldermask Top")
		(3 "B.Mask" user "Board Geometry/Soldermask Bottom")
		(17 "Dwgs.User" user "User.Drawings")
		(19 "Cmts.User" user "User.Comments")
		(21 "Eco1.User" user "User.Eco1")
		(23 "Eco2.User" user "User.Eco2")
		(25 "Edge.Cuts" user "Board Geometry/Outline")
		(27 "Margin" user)
		(31 "F.CrtYd" user "Package Geometry/Place Bound Top")
		(29 "B.CrtYd" user "Package Geometry/Place Bound Bottom")
		(35 "F.Fab" user "Ref Des/Assembly Top")
		(33 "B.Fab" user "Ref Des/Assembly Bottom")
	)
	(footprint ""
		(layer "F.Cu")
		(at 406.516078 -121.083832 90)
		(property "Reference" "R1W19"
			(at -0.8382 -0.67818 90)
			(unlocked yes)
			(layer "F.SilkS")
			(effects
				(font
					(size 0.4064 0.254)
					(thickness 0.1524)
				)
				(justify left)
			)
		)
		(property "Value" ""
			(at 0 0 90)
			(layer "F.Fab")
			(effects
				(font
					(size 1.27 1.27)
				)
			)
		)
		(duplicate_pad_numbers_are_jumpers no)
		(fp_poly
			(pts
				(xy -0.2794 -0.1016) (xy 0.2794 -0.1016) (xy 0.2794 0.9906) (xy -0.2794 0.9906)
			)
			(stroke
				(width 0)
				(type default)
			)
			(fill no)
			(layer "F.CrtYd")
		)
		(fp_line
			(start 0.2794 -0.1016)
			(end -0.2794 -0.1016)
			(stroke
				(width 0.1)
				(type default)
			)
			(layer "F.Fab")
		)
		(fp_line
			(start -0.2794 -0.1016)
			(end -0.2794 0.9906)
			(stroke
				(width 0.1)
				(type default)
			)
			(layer "F.Fab")
		)
		(fp_line
			(start 0.2794 0.9906)
			(end 0.2794 -0.1016)
			(stroke
				(width 0.1)
				(type default)
			)
			(layer "F.Fab")
		)
		(fp_line
			(start -0.2794 0.9906)
			(end 0.2794 0.9906)
			(stroke
				(width 0.1)
				(type default)
			)
			(layer "F.Fab")
		)
		(pad "1" smd rect
			(at 0 0 90)
			(size 0.508 0.508)
			(layers "F.Cu" "F.Mask" "F.Paste")
			(net "USB2_P02_DN_R")
		)
		(pad "2" smd rect
			(at 0 0.889 90)
			(size 0.508 0.508)
			(layers "F.Cu" "F.Mask" "F.Paste")
			(net "USB2_P02_DN")
		)
		(zone
			(layer "F.Cu")
			(hatch none 0.5)
			(connect_pads
				(clearance 0)
			)
			(min_thickness 0.25)
			(keepout
				(tracks allowed)
				(vias not_allowed)
				(pads allowed)
				(copperpour not_allowed)
				(footprints allowed)
			)
			(placement
				(enabled no)
				(sheetname "")
			)
			(fill
				(thermal_gap 0.5)
				(thermal_bridge_width 0.5)
				(island_removal_mode 0)
			)
			(polygon
				(pts
					(xy 406.770078 -120.829832) (xy 406.770078 -121.337832) (xy 407.151078 -121.337832) (xy 407.151078 -120.829832)
				)
			)
		)
		(zone
			(layer "F.Cu")
			(hatch none 0.5)
			(connect_pads
				(clearance 0)
			)
			(min_thickness 0.25)
			(keepout
				(tracks not_allowed)
				(vias allowed)
				(pads allowed)
				(copperpour not_allowed)
				(footprints allowed)
			)
			(placement
				(enabled no)
				(sheetname "")
			)
			(fill
				(thermal_gap 0.5)
				(thermal_bridge_width 0.5)
				(island_removal_mode 0)
			)
			(polygon
				(pts
					(xy 407.151078 -120.829832) (xy 407.151078 -121.337832) (xy 406.770078 -121.337832) (xy 406.770078 -120.829832)
				)
			)
		)
	)
	(footprint ""
		(layer "F.Cu")
		(at 14.986 -82.169 -90)
		(property "Reference" "R1D18"
			(at 0 0 270)
			(layer "F.SilkS")
			(hide yes)
			(effects
				(font
					(size 1.27 1.27)
				)
			)
		)
		(property "Value" ""
			(at 0 0 270)
			(layer "F.Fab")
			(effects
				(font
					(size 1.27 1.27)
				)
			)
		)
		(duplicate_pad_numbers_are_jumpers no)
		(fp_poly
			(pts
				(xy -0.2794 -0.1016) (xy 0.2794 -0.1016) (xy 0.2794 0.9906) (xy -0.2794 0.9906)
			)
			(stroke
				(width 0)
				(type default)
			)
			(fill no)
			(layer "F.CrtYd")
		)
		(fp_line
			(start -0.2794 0.9906)
			(end 0.2794 0.9906)
			(stroke
				(width 0.1)
				(type default)
			)
			(layer "F.Fab")
		)
		(fp_line
			(start 0.2794 0.9906)
			(end 0.2794 -0.1016)
			(stroke
				(width 0.1)
				(type default)
			)
			(layer "F.Fab")
		)
		(fp_line
			(start -0.2794 -0.1016)
			(end -0.2794 0.9906)
			(stroke
				(width 0.1)
				(type default)
			)
			(layer "F.Fab")
		)
		(fp_line
			(start 0.2794 -0.1016)
			(end -0.2794 -0.1016)
			(stroke
				(width 0.1)
				(type default)
			)
			(layer "F.Fab")
		)
		(pad "1" smd rect
			(at 0 0 270)
			(size 0.508 0.508)
			(layers "F.Cu" "F.Mask" "F.Paste")
			(net "A_HSC_HIGH_EN")
		)
		(pad "2" smd rect
			(at 0 0.889 270)
			(size 0.508 0.508)
			(layers "F.Cu" "F.Mask" "F.Paste")
			(net "AGND_HSC")
		)
		(zone
			(layer "F.Cu")
			(hatch none 0.5)
			(connect_pads
				(clearance 0)
			)
			(min_thickness 0.25)
			(keepout
				(tracks not_allowed)
				(vias allowed)
				(pads allowed)
				(copperpour not_allowed)
				(footprints allowed)
			)
			(placement
				(enabled no)
				(sheetname "")
			)
			(fill
				(thermal_gap 0.5)
				(thermal_bridge_width 0.5)
				(island_removal_mode 0)
			)
			(polygon
				(pts
					(xy 14.351 -82.423) (xy 14.351 -81.915) (xy 14.732 -81.915) (xy 14.732 -82.423)
				)
			)
		)
		(zone
			(layer "F.Cu")
			(hatch none 0.5)
			(connect_pads
				(clearance 0)
			)
			(min_thickness 0.25)
			(keepout
				(tracks allowed)
				(vias not_allowed)
				(pads allowed)
				(copperpour not_allowed)
				(footprints allowed)
			)
			(placement
				(enabled no)
				(sheetname "")
			)
			(fill
				(thermal_gap 0.5)
				(thermal_bridge_width 0.5)
				(island_removal_mode 0)
			)
			(polygon
				(pts
					(xy 14.732 -82.423) (xy 14.732 -81.915) (xy 14.351 -81.915) (xy 14.351 -82.423)
				)
			)
		)
	)
	(footprint ""
		(layer "F.Cu")
		(at 363.87024 -140.88237 180)
		(property "Reference" "C7A28"
			(at 0 0 180)
			(layer "F.SilkS")
			(hide yes)
			(effects
				(font
					(size 1.27 1.27)
				)
			)
		)
		(property "Value" ""
			(at 0 0 180)
			(layer "F.Fab")
			(effects
				(font
					(size 1.27 1.27)
				)
			)
		)
		(duplicate_pad_numbers_are_jumpers no)
		(fp_rect
			(start 0.3048 -0.1016)
			(end -0.3048 0.9906)
			(stroke
				(width 0)
				(type default)
			)
			(fill no)
			(layer "F.CrtYd")
		)
		(fp_line
			(start 0.3048 0.9906)
			(end 0.3048 -0.1016)
			(stroke
				(width 0.1)
				(type default)
			)
			(layer "F.Fab")
		)
		(fp_line
			(start 0.3048 -0.1016)
			(end -0.3048 -0.1016)
			(stroke
				(width 0.1)
				(type default)
			)
			(layer "F.Fab")
		)
		(fp_line
			(start -0.3048 0.9906)
			(end 0.3048 0.9906)
			(stroke
				(width 0.1)
				(type default)
			)
			(layer "F.Fab")
		)
		(fp_line
			(start -0.3048 -0.1016)
			(end -0.3048 0.9906)
			(stroke
				(width 0.1)
				(type default)
			)
			(layer "F.Fab")
		)
		(pad "1" smd rect
			(at 0 0 180)
			(size 0.508 0.508)
			(layers "F.Cu" "F.Mask" "F.Paste")
			(net "VR_PVDDQ_DEF_AVSP")
		)
		(pad "2" smd rect
			(at 0 0.889 180)
			(size 0.508 0.508)
			(layers "F.Cu" "F.Mask" "F.Paste")
			(net "VSENSE_PVDDQ_DEF_N")
		)
		(zone
			(layer "F.Cu")
			(hatch none 0.5)
			(connect_pads
				(clearance 0)
			)
			(min_thickness 0.25)
			(keepout
				(tracks allowed)
				(vias not_allowed)
				(pads allowed)
				(copperpour not_allowed)
				(footprints allowed)
			)
			(placement
				(enabled no)
				(sheetname "")
			)
			(fill
				(thermal_gap 0.5)
				(thermal_bridge_width 0.5)
				(island_removal_mode 0)
			)
			(polygon
				(pts
					(xy 363.61624 -141.13637) (xy 364.12424 -141.13637) (xy 364.12424 -141.51737) (xy 363.61624 -141.51737)
				)
			)
		)
		(zone
			(layer "F.Cu")
			(hatch none 0.5)
			(connect_pads
				(clearance 0)
			)
			(min_thickness 0.25)
			(keepout
				(tracks not_allowed)
				(vias allowed)
				(pads allowed)
				(copperpour not_allowed)
				(footprints allowed)
			)
			(placement
				(enabled no)
				(sheetname "")
			)
			(fill
				(thermal_gap 0.5)
				(thermal_bridge_width 0.5)
				(island_removal_mode 0)
			)
			(polygon
				(pts
					(xy 363.61624 -141.13637) (xy 364.12424 -141.13637) (xy 364.12424 -141.51737) (xy 363.61624 -141.51737)
				)
			)
		)
	)
)
